# T6G (Grand Teton) — schematic netlist excerpt (pin names and nets, part order shuffled) for the footprints in the layout excerpt that follows; sources: Cadence DE-HDL packaged netlist, KiCad conversion of 04192023_DAF0TMB3IC0_F0TG_MB_C_brd_V02_OCP.brd

U320  74LVC1G66GV  IC  pkg SC74AXA  page 133
  Y  = CLK_50M_NCSI_OCP_SFF
  Z  = CLK_50M_NCSI_OCP_SFF_ISO_R
  GND  = GND
  E  = FB_BMC_ISOLATE
  VCC  = P3V3_AUX

C2591  Q_CAP  22UF 4V 20% X6S  pkg C0402  page 70 : A = PVDDCR_SOC_P0 ; B = GND

(kicad_pcb
	(version 20260206)
	(generator "pcbnew")
	(generator_version "10.0")
	(general
		(thickness 1.6)
		(legacy_teardrops no)
	)
	(paper "A4")
	(title_block
		(title "04192023_DAF0TMB3IC0_F0TG_MB_C_brd_V02_OCP.brd")
		(comment 1 "Grand Teton / footprints 3999-4000 of 8354")
	)
	(layers
		(0 "F.Cu" signal "TOP")
		(4 "In1.Cu" signal "GND")
		(6 "In2.Cu" signal "IN1")
		(8 "In3.Cu" signal "GND1")
		(10 "In4.Cu" signal "IN2")
		(12 "In5.Cu" signal "GND2")
		(14 "In6.Cu" signal "IN3")
		(16 "In7.Cu" signal "GND3")
		(18 "In8.Cu" signal "VCC")
		(20 "In9.Cu" signal "VCC1")
		(22 "In10.Cu" signal "GND4")
		(24 "In11.Cu" signal "IN4")
		(26 "In12.Cu" signal "GND5")
		(28 "In13.Cu" signal "IN5")
		(30 "In14.Cu" signal "GND6")
		(32 "In15.Cu" signal "IN6")
		(34 "In16.Cu" signal "GND7")
		(2 "B.Cu" signal "BOTTOM")
		(9 "F.Adhes" user "F.Adhesive")
		(11 "B.Adhes" user "B.Adhesive")
		(13 "F.Paste" user "Package Geometry/Pastemask Top")
		(15 "B.Paste" user "Package Geometry/Pastemask Bottom")
		(5 "F.SilkS" user "Ref Des/Silkscreen Top")
		(7 "B.SilkS" user "Ref Des/Silkscreen Bottom")
		(1 "F.Mask" user "Board Geometry/Soldermask Top")
		(3 "B.Mask" user "Board Geometry/Soldermask Bottom")
		(17 "Dwgs.User" user "User.Drawings")
		(19 "Cmts.User" user "User.Comments")
		(21 "Eco1.User" user "User.Eco1")
		(23 "Eco2.User" user "User.Eco2")
		(25 "Edge.Cuts" user "Board Geometry/Outline")
		(27 "Margin" user)
		(31 "F.CrtYd" user "Package Geometry/Place Bound Top")
		(29 "B.CrtYd" user "Package Geometry/Place Bound Bottom")
		(35 "F.Fab" user "Ref Des/Assembly Top")
		(33 "B.Fab" user "Ref Des/Assembly Bottom")
	)
	(footprint ""
		(layer "F.Cu")
		(at 365.835692 -257.455162 180)
		(property "Reference" "C2591"
			(at 0 0 180)
			(layer "F.SilkS")
			(hide yes)
			(effects
				(font
					(size 1.27 1.27)
				)
			)
		)
		(property "Value" ""
			(at 0 0 180)
			(layer "F.Fab")
			(effects
				(font
					(size 1.27 1.27)
				)
			)
		)
		(duplicate_pad_numbers_are_jumpers no)
		(fp_line
			(start 0.7874 0.4064)
			(end -0.7874 0.4064)
			(stroke
				(width 0.1524)
				(type default)
			)
			(layer "F.SilkS")
		)
		(fp_line
			(start 0.7874 -0.4064)
			(end 0.7874 0.4064)
			(stroke
				(width 0.1524)
				(type default)
			)
			(layer "F.SilkS")
		)
		(fp_line
			(start -0.7874 0.4064)
			(end -0.7874 -0.4064)
			(stroke
				(width 0.1524)
				(type default)
			)
			(layer "F.SilkS")
		)
		(fp_line
			(start -0.7874 -0.4064)
			(end 0.7874 -0.4064)
			(stroke
				(width 0.1524)
				(type default)
			)
			(layer "F.SilkS")
		)
		(fp_line
			(start 0.67945 0.3048)
			(end 0.120396 0.3048)
			(stroke
				(width 0.1)
				(type default)
			)
			(layer "F.Fab")
		)
		(fp_line
			(start 0.67945 -0.3048)
			(end 0.67945 0.3048)
			(stroke
				(width 0.1)
				(type default)
			)
			(layer "F.Fab")
		)
		(fp_line
			(start 0.12065 -0.2794)
			(end 0.12065 -0.3048)
			(stroke
				(width 0.1)
				(type default)
			)
			(layer "F.Fab")
		)
		(fp_line
			(start 0.12065 -0.3048)
			(end 0.67945 -0.3048)
			(stroke
				(width 0.1)
				(type default)
			)
			(layer "F.Fab")
		)
		(fp_line
			(start 0.120396 0.3048)
			(end 0.120396 0.2794)
			(stroke
				(width 0.1)
				(type default)
			)
			(layer "F.Fab")
		)
		(fp_line
			(start 0.120396 0.2794)
			(end -0.12065 0.2794)
			(stroke
				(width 0.1)
				(type default)
			)
			(layer "F.Fab")
		)
		(fp_line
			(start -0.12065 0.3048)
			(end -0.67945 0.3048)
			(stroke
				(width 0.1)
				(type default)
			)
			(layer "F.Fab")
		)
		(fp_line
			(start -0.12065 0.2794)
			(end -0.12065 0.3048)
			(stroke
				(width 0.1)
				(type default)
			)
			(layer "F.Fab")
		)
		(fp_line
			(start -0.12065 -0.2794)
			(end 0.12065 -0.2794)
			(stroke
				(width 0.1)
				(type default)
			)
			(layer "F.Fab")
		)
		(fp_line
			(start -0.12065 -0.305054)
			(end -0.12065 -0.2794)
			(stroke
				(width 0.1)
				(type default)
			)
			(layer "F.Fab")
		)
		(fp_line
			(start -0.67945 0.3048)
			(end -0.67945 -0.305054)
			(stroke
				(width 0.1)
				(type default)
			)
			(layer "F.Fab")
		)
		(fp_line
			(start -0.67945 -0.305054)
			(end -0.12065 -0.305054)
			(stroke
				(width 0.1)
				(type default)
			)
			(layer "F.Fab")
		)
		(pad "1" smd circle
			(at -0.40005 0 180)
			(size 0 0)
			(layers "F.Cu" "F.Mask" "F.Paste")
			(net "PVDDCR_SOC_P0")
		)
		(pad "2" smd circle
			(at 0.40005 0 180)
			(size 0 0)
			(layers "F.Cu" "F.Mask" "F.Paste")
			(net "GND")
		)
	)
	(footprint ""
		(layer "F.Cu")
		(at 380.39548 -33.228788 180)
		(property "Reference" "U320"
			(at 1.088136 2.603246 0)
			(unlocked yes)
			(layer "F.SilkS")
			(effects
				(font
					(size 0.7874 0.5842)
					(thickness 0.1524)
				)
				(justify left)
			)
		)
		(property "Value" ""
			(at 0 0 180)
			(layer "F.Fab")
			(effects
				(font
					(size 1.27 1.27)
				)
			)
		)
		(duplicate_pad_numbers_are_jumpers no)
		(fp_line
			(start 2.032 1.549908)
			(end -2.032 1.549908)
			(stroke
				(width 0.1524)
				(type default)
			)
			(layer "F.SilkS")
		)
		(fp_line
			(start 2.032 -1.549908)
			(end 2.032 1.549908)
			(stroke
				(width 0.1524)
				(type default)
			)
			(layer "F.SilkS")
		)
		(fp_line
			(start -2.032 1.549908)
			(end -2.032 -1.549908)
			(stroke
				(width 0.1524)
				(type default)
			)
			(layer "F.SilkS")
		)
		(fp_line
			(start -2.032 -1.549908)
			(end 2.032 -1.549908)
			(stroke
				(width 0.1524)
				(type default)
			)
			(layer "F.SilkS")
		)
		(fp_poly
			(pts
				(xy -2.9464 -1.2192) (xy -2.9464 -0.7112) (xy -2.1844 -0.9652)
			)
			(stroke
				(width 0)
				(type default)
			)
			(fill yes)
			(layer "F.SilkS")
		)
		(fp_line
			(start 0.849884 1.549908)
			(end 0.849884 -1.549908)
			(stroke
				(width 0.1)
				(type default)
			)
			(layer "F.Fab")
		)
		(fp_line
			(start 0.849884 -1.549908)
			(end -0.849884 -1.549908)
			(stroke
				(width 0.1)
				(type default)
			)
			(layer "F.Fab")
		)
		(fp_line
			(start -0.849884 1.549908)
			(end 0.849884 1.549908)
			(stroke
				(width 0.1)
				(type default)
			)
			(layer "F.Fab")
		)
		(fp_line
			(start -0.849884 -1.549908)
			(end -0.849884 1.549908)
			(stroke
				(width 0.1)
				(type default)
			)
			(layer "F.Fab")
		)
		(fp_poly
			(pts
				(xy -2.9464 -1.2192) (xy -2.9464 -0.7112) (xy -2.1844 -0.9652)
			)
			(stroke
				(width 0)
				(type default)
			)
			(fill yes)
			(layer "F.Fab")
		)
		(pad "1" smd rect
			(at -1.225042 -0.94996 90)
			(size 0.4572 1.3208)
			(layers "F.Cu" "F.Mask" "F.Paste")
			(net "CLK_50M_NCSI_OCP_SFF")
		)
		(pad "2" smd rect
			(at -1.225042 0 90)
			(size 0.4572 1.3208)
			(layers "F.Cu" "F.Mask" "F.Paste")
			(net "CLK_50M_NCSI_OCP_SFF_ISO_R")
		)
		(pad "3" smd rect
			(at -1.225042 0.94996 90)
			(size 0.4572 1.3208)
			(layers "F.Cu" "F.Mask" "F.Paste")
			(net "GND")
		)
		(pad "4" smd rect
			(at 1.225042 0.94996 90)
			(size 0.4572 1.3208)
			(layers "F.Cu" "F.Mask" "F.Paste")
			(net "FB_BMC_ISOLATE")
		)
		(pad "5" smd rect
			(at 1.225042 -0.94996 90)
			(size 0.4572 1.3208)
			(layers "F.Cu" "F.Mask" "F.Paste")
			(net "P3V3_AUX")
		)
	)
)
